(kicad_pcb
	(version 20241229)
	(generator "pcbnew")
	(generator_version "9.0")
	(general
		(thickness 1.552)
		(legacy_teardrops no)
	)
	(paper "A4")
	(title_block
		(date "2023-07-25")
		(rev "1.1.4")
		(comment 9 "footprints 76-80 of 379")
	)
	(layers
		(0 "F.Cu" signal)
		(4 "In1.Cu" signal)
		(6 "In2.Cu" signal)
		(8 "In3.Cu" signal)
		(10 "In4.Cu" signal)
		(12 "In5.Cu" signal)
		(14 "In6.Cu" signal)
		(2 "B.Cu" signal)
		(9 "F.Adhes" user "F.Adhesive")
		(11 "B.Adhes" user "B.Adhesive")
		(13 "F.Paste" user)
		(15 "B.Paste" user)
		(5 "F.SilkS" user "F.Silkscreen")
		(7 "B.SilkS" user "B.Silkscreen")
		(1 "F.Mask" user)
		(3 "B.Mask" user)
		(17 "Dwgs.User" user "User.Drawings")
		(19 "Cmts.User" user "User.Comments")
		(21 "Eco1.User" user "User.Eco1")
		(23 "Eco2.User" user "User.Eco2")
		(25 "Edge.Cuts" user)
		(27 "Margin" user)
		(31 "F.CrtYd" user "F.Courtyard")
		(29 "B.CrtYd" user "B.Courtyard")
		(35 "F.Fab" user)
		(33 "B.Fab" user)
	)
	(footprint "antmicro-footprints:TP_SMD_0.75mm"
		(layer "F.Cu")
		(at 99 69.48)
		(property "Reference" "TP24"
			(at -3.22 0.39 0)
			(layer "F.SilkS")
			(effects
				(font
					(size 0.65 0.65)
					(thickness 0.15)
				)
				(justify left bottom)
			)
		)
		(property "Value" "TP_0.75mm_SMD"
			(at 0 1.2 0)
			(layer "F.Fab")
			(hide yes)
			(effects
				(font
					(size 0.7 0.7)
					(thickness 0.15)
				)
				(justify left bottom)
			)
		)
		(property "Description" "SMT test point"
			(at 0 0 0)
			(layer "F.Fab")
			(hide yes)
			(effects
				(font
					(size 1.27 1.27)
					(thickness 0.15)
				)
			)
		)
		(property "Author" "Antmicro"
			(at 0 0 0)
			(layer "F.Fab")
			(hide yes)
			(effects
				(font
					(size 1 1)
					(thickness 0.15)
				)
			)
		)
		(property "License" "Apache-2.0"
			(at 0 0 0)
			(layer "F.Fab")
			(hide yes)
			(effects
				(font
					(size 1 1)
					(thickness 0.15)
				)
			)
		)
		(property "MPN" ""
			(at 0 0 0)
			(layer "F.Fab")
			(hide yes)
			(effects
				(font
					(size 1 1)
					(thickness 0.15)
				)
			)
		)
		(property "Manufacturer" ""
			(at 0 0 0)
			(layer "F.Fab")
			(hide yes)
			(effects
				(font
					(size 1 1)
					(thickness 0.15)
				)
			)
		)
		(sheetname "/SDI/")
		(sheetfile "sdi.kicad_sch")
		(attr exclude_from_pos_files)
		(fp_circle
			(center 0 0)
			(end 0.475 0)
			(stroke
				(width 0.05)
				(type default)
			)
			(fill no)
			(layer "F.CrtYd")
		)
		(fp_text user "License: Apache-2.0"
			(at -0.4 5.101 0)
			(layer "F.Fab")
			(effects
				(font
					(size 0.7 0.7)
					(thickness 0.15)
				)
				(justify left bottom)
			)
		)
		(fp_text user "${REFERENCE}"
			(at -0.4 2.7 0)
			(layer "F.Fab")
			(effects
				(font
					(size 0.7 0.7)
					(thickness 0.15)
				)
				(justify left bottom)
			)
		)
		(fp_text user "Author: Antmicro"
			(at -0.4 3.901 0)
			(layer "F.Fab")
			(effects
				(font
					(size 0.7 0.7)
					(thickness 0.15)
				)
				(justify left bottom)
			)
		)
		(pad "1" smd circle
			(at 0 0)
			(size 0.75 0.75)
			(layers "F.Cu" "F.Mask")
			(net 214 "/SDI/SDI_STAT0")
			(pinfunction "1")
			(pintype "passive")
		)
	)
	(footprint "antmicro-footprints:R_0402_1005Metric"
		(layer "F.Cu")
		(at 130.75 116.75 -90)
		(descr "Resistor SMD 0402")
		(tags "resistor SMD 0402")
		(property "Reference" "R109"
			(at -0.81 -0.28 270)
			(layer "F.SilkS")
			(effects
				(font
					(size 0.65 0.65)
					(thickness 0.15)
				)
				(justify left bottom)
			)
		)
		(property "Value" "R_0R_0402"
			(at 0 1.4 270)
			(layer "F.Fab")
			(hide yes)
			(effects
				(font
					(size 0.7 0.7)
					(thickness 0.15)
				)
				(justify left bottom)
			)
		)
		(property "Datasheet" "https://industrial.panasonic.com/cdbs/www-data/pdf/RDA0000/AOA0000C301.pdf"
			(at 0 0 270)
			(layer "F.Fab")
			(hide yes)
			(effects
				(font
					(size 1.27 1.27)
					(thickness 0.15)
				)
			)
		)
		(property "Description" "SMD Chip Resistor, Jumper, 0 ohm, 100 mW, 0402 [1005 Metric], Thick Film, General Purpose"
			(at 0 0 270)
			(layer "F.Fab")
			(hide yes)
			(effects
				(font
					(size 1.27 1.27)
					(thickness 0.15)
				)
			)
		)
		(property "Author" "Antmicro"
			(at 14 247.5 0)
			(layer "F.Fab")
			(hide yes)
			(effects
				(font
					(size 1 1)
					(thickness 0.15)
				)
			)
		)
		(property "Current" "1A"
			(at 14 247.5 0)
			(layer "F.Fab")
			(hide yes)
			(effects
				(font
					(size 1 1)
					(thickness 0.15)
				)
			)
		)
		(property "License" "Apache-2.0"
			(at 14 247.5 0)
			(layer "F.Fab")
			(hide yes)
			(effects
				(font
					(size 1 1)
					(thickness 0.15)
				)
			)
		)
		(property "MPN" "ERJ2GE0R00X"
			(at 14 247.5 0)
			(layer "F.Fab")
			(hide yes)
			(effects
				(font
					(size 1 1)
					(thickness 0.15)
				)
			)
		)
		(property "Manufacturer" "Panasonic"
			(at 14 247.5 0)
			(layer "F.Fab")
			(hide yes)
			(effects
				(font
					(size 1 1)
					(thickness 0.15)
				)
			)
		)
		(property "Tolerance" "~"
			(at 14 247.5 0)
			(layer "F.Fab")
			(hide yes)
			(effects
				(font
					(size 1 1)
					(thickness 0.15)
				)
			)
		)
		(property "Val" "0R"
			(at 14 247.5 0)
			(layer "F.Fab")
			(hide yes)
			(effects
				(font
					(size 1 1)
					(thickness 0.15)
				)
			)
		)
		(sheetname "/Peripherals/")
		(sheetfile "peripherals.kicad_sch")
		(attr smd)
		(fp_rect
			(start -0.925 -0.47)
			(end 0.925 0.47)
			(stroke
				(width 0.05)
				(type default)
			)
			(fill no)
			(layer "F.CrtYd")
		)
		(fp_rect
			(start -0.5 -0.25)
			(end 0.5 0.25)
			(stroke
				(width 0.15)
				(type solid)
			)
			(fill no)
			(layer "F.Fab")
		)
		(fp_text user "Author: Antmicro"
			(at -0.95 4.169 270)
			(layer "F.Fab")
			(effects
				(font
					(size 0.7 0.7)
					(thickness 0.15)
				)
				(justify left bottom)
			)
		)
		(fp_text user "License: Apache-2.0"
			(at -0.95 5.169 270)
			(layer "F.Fab")
			(effects
				(font
					(size 0.7 0.7)
					(thickness 0.15)
				)
				(justify left bottom)
			)
		)
		(fp_text user "${REFERENCE}"
			(at -0.95 3.168 270)
			(layer "F.Fab")
			(effects
				(font
					(size 0.7 0.7)
					(thickness 0.15)
				)
				(justify left bottom)
			)
		)
		(pad "1" smd roundrect
			(at -0.48 0 270)
			(size 0.59 0.64)
			(layers "F.Cu" "F.Mask" "F.Paste")
			(roundrect_rratio 0.25)
			(net 101 "SDA")
			(pintype "passive")
		)
		(pad "2" smd roundrect
			(at 0.48 0 270)
			(size 0.59 0.64)
			(layers "F.Cu" "F.Mask" "F.Paste")
			(roundrect_rratio 0.25)
			(net 323 "Net-(J6-Pad39)")
			(pintype "passive")
		)
	)
	(footprint "antmicro-footprints:R_0402_1005Metric"
		(layer "F.Cu")
		(at 129.75 116.75 -90)
		(descr "Resistor SMD 0402")
		(tags "resistor SMD 0402")
		(property "Reference" "R130"
			(at -0.81 -0.28 270)
			(layer "F.SilkS")
			(effects
				(font
					(size 0.65 0.65)
					(thickness 0.15)
				)
				(justify left bottom)
			)
		)
		(property "Value" "R_0R_0402"
			(at 0 1.4 270)
			(layer "F.Fab")
			(hide yes)
			(effects
				(font
					(size 0.7 0.7)
					(thickness 0.15)
				)
				(justify left bottom)
			)
		)
		(property "Datasheet" "https://industrial.panasonic.com/cdbs/www-data/pdf/RDA0000/AOA0000C301.pdf"
			(at 0 0 270)
			(layer "F.Fab")
			(hide yes)
			(effects
				(font
					(size 1.27 1.27)
					(thickness 0.15)
				)
			)
		)
		(property "Description" "SMD Chip Resistor, Jumper, 0 ohm, 100 mW, 0402 [1005 Metric], Thick Film, General Purpose"
			(at 0 0 270)
			(layer "F.Fab")
			(hide yes)
			(effects
				(font
					(size 1.27 1.27)
					(thickness 0.15)
				)
			)
		)
		(property "Author" "Antmicro"
			(at 13 246.5 0)
			(layer "F.Fab")
			(hide yes)
			(effects
				(font
					(size 1 1)
					(thickness 0.15)
				)
			)
		)
		(property "Current" "1A"
			(at 13 246.5 0)
			(layer "F.Fab")
			(hide yes)
			(effects
				(font
					(size 1 1)
					(thickness 0.15)
				)
			)
		)
		(property "License" "Apache-2.0"
			(at 13 246.5 0)
			(layer "F.Fab")
			(hide yes)
			(effects
				(font
					(size 1 1)
					(thickness 0.15)
				)
			)
		)
		(property "MPN" "ERJ2GE0R00X"
			(at 13 246.5 0)
			(layer "F.Fab")
			(hide yes)
			(effects
				(font
					(size 1 1)
					(thickness 0.15)
				)
			)
		)
		(property "Manufacturer" "Panasonic"
			(at 13 246.5 0)
			(layer "F.Fab")
			(hide yes)
			(effects
				(font
					(size 1 1)
					(thickness 0.15)
				)
			)
		)
		(property "Tolerance" "~"
			(at 13 246.5 0)
			(layer "F.Fab")
			(hide yes)
			(effects
				(font
					(size 1 1)
					(thickness 0.15)
				)
			)
		)
		(property "Val" "0R"
			(at 13 246.5 0)
			(layer "F.Fab")
			(hide yes)
			(effects
				(font
					(size 1 1)
					(thickness 0.15)
				)
			)
		)
		(sheetname "/Peripherals/")
		(sheetfile "peripherals.kicad_sch")
		(attr smd)
		(fp_rect
			(start -0.925 -0.47)
			(end 0.925 0.47)
			(stroke
				(width 0.05)
				(type default)
			)
			(fill no)
			(layer "F.CrtYd")
		)
		(fp_rect
			(start -0.5 -0.25)
			(end 0.5 0.25)
			(stroke
				(width 0.15)
				(type solid)
			)
			(fill no)
			(layer "F.Fab")
		)
		(fp_text user "Author: Antmicro"
			(at -0.95 4.169 270)
			(layer "F.Fab")
			(effects
				(font
					(size 0.7 0.7)
					(thickness 0.15)
				)
				(justify left bottom)
			)
		)
		(fp_text user "${REFERENCE}"
			(at -0.95 3.168 270)
			(layer "F.Fab")
			(effects
				(font
					(size 0.7 0.7)
					(thickness 0.15)
				)
				(justify left bottom)
			)
		)
		(fp_text user "License: Apache-2.0"
			(at -0.95 5.169 270)
			(layer "F.Fab")
			(effects
				(font
					(size 0.7 0.7)
					(thickness 0.15)
				)
				(justify left bottom)
			)
		)
		(pad "1" smd roundrect
			(at -0.48 0 270)
			(size 0.59 0.64)
			(layers "F.Cu" "F.Mask" "F.Paste")
			(roundrect_rratio 0.25)
			(net 106 "/Peripherals/FFC2_VSYNC1")
			(pintype "passive")
		)
		(pad "2" smd roundrect
			(at 0.48 0 270)
			(size 0.59 0.64)
			(layers "F.Cu" "F.Mask" "F.Paste")
			(roundrect_rratio 0.25)
			(net 345 "Net-(J6-Pad34)")
			(pintype "passive")
		)
	)
	(footprint "antmicro-footprints:R_0402_1005Metric"
		(layer "F.Cu")
		(at 137.115 108.55 180)
		(descr "Resistor SMD 0402")
		(tags "resistor SMD 0402")
		(property "Reference" "R35"
			(at 3.085 -0.39 180)
			(layer "F.SilkS")
			(effects
				(font
					(size 0.65 0.65)
					(thickness 0.15)
				)
				(justify left bottom)
			)
		)
		(property "Value" "R_18k7_0402"
			(at 0 1.4 180)
			(layer "F.Fab")
			(hide yes)
			(effects
				(font
					(size 0.7 0.7)
					(thickness 0.15)
				)
				(justify left bottom)
			)
		)
		(property "Datasheet" "https://www.bourns.com/docs/product-datasheets/cr.pdf"
			(at 0 0 180)
			(layer "F.Fab")
			(hide yes)
			(effects
				(font
					(size 1.27 1.27)
					(thickness 0.15)
				)
			)
		)
		(property "Description" "SMD Chip Resistor"
			(at 0 0 180)
			(layer "F.Fab")
			(hide yes)
			(effects
				(font
					(size 1.27 1.27)
					(thickness 0.15)
				)
			)
		)
		(property "Author" "Antmicro"
			(at 274.23 217.1 0)
			(layer "F.Fab")
			(hide yes)
			(effects
				(font
					(size 1 1)
					(thickness 0.15)
				)
			)
		)
		(property "License" "Apache-2.0"
			(at 274.23 217.1 0)
			(layer "F.Fab")
			(hide yes)
			(effects
				(font
					(size 1 1)
					(thickness 0.15)
				)
			)
		)
		(property "MPN" "CR0402-FX-1872GLF"
			(at 274.23 217.1 0)
			(layer "F.Fab")
			(hide yes)
			(effects
				(font
					(size 1 1)
					(thickness 0.15)
				)
			)
		)
		(property "Manufacturer" "Bourns"
			(at 274.23 217.1 0)
			(layer "F.Fab")
			(hide yes)
			(effects
				(font
					(size 1 1)
					(thickness 0.15)
				)
			)
		)
		(property "Tolerance" "1%"
			(at 274.23 217.1 0)
			(layer "F.Fab")
			(hide yes)
			(effects
				(font
					(size 1 1)
					(thickness 0.15)
				)
			)
		)
		(property "Val" "18k7"
			(at 274.23 217.1 0)
			(layer "F.Fab")
			(hide yes)
			(effects
				(font
					(size 1 1)
					(thickness 0.15)
				)
			)
		)
		(sheetname "/Power Supply/")
		(sheetfile "supply.kicad_sch")
		(attr smd)
		(fp_rect
			(start -0.925 -0.47)
			(end 0.925 0.47)
			(stroke
				(width 0.05)
				(type default)
			)
			(fill no)
			(layer "F.CrtYd")
		)
		(fp_rect
			(start -0.5 -0.25)
			(end 0.5 0.25)
			(stroke
				(width 0.15)
				(type solid)
			)
			(fill no)
			(layer "F.Fab")
		)
		(fp_text user "Author: Antmicro"
			(at -0.95 4.169 180)
			(layer "F.Fab")
			(effects
				(font
					(size 0.7 0.7)
					(thickness 0.15)
				)
				(justify left bottom)
			)
		)
		(fp_text user "${REFERENCE}"
			(at -0.95 3.168 180)
			(layer "F.Fab")
			(effects
				(font
					(size 0.7 0.7)
					(thickness 0.15)
				)
				(justify left bottom)
			)
		)
		(fp_text user "License: Apache-2.0"
			(at -0.95 5.169 180)
			(layer "F.Fab")
			(effects
				(font
					(size 0.7 0.7)
					(thickness 0.15)
				)
				(justify left bottom)
			)
		)
		(pad "1" smd roundrect
			(at -0.48 0 180)
			(size 0.59 0.64)
			(layers "F.Cu" "F.Mask" "F.Paste")
			(roundrect_rratio 0.25)
			(net 283 "Net-(U10-ADJ)")
			(pintype "passive")
		)
		(pad "2" smd roundrect
			(at 0.48 0 180)
			(size 0.59 0.64)
			(layers "F.Cu" "F.Mask" "F.Paste")
			(roundrect_rratio 0.25)
			(net 284 "Net-(U10-V_{OUT})")
			(pintype "passive")
		)
	)
	(footprint "antmicro-footprints:LED_0603_1608Metric_G"
		(layer "F.Cu")
		(at 141.46 82.5 180)
		(descr "LED SMD 0603 Green")
		(tags "LED SMD 0603 Green")
		(property "Reference" "D12"
			(at -3.27 0.36 0)
			(layer "F.SilkS")
			(effects
				(font
					(size 0.65 0.65)
					(thickness 0.15)
				)
				(justify right top)
			)
		)
		(property "Value" "LED_G_0603_LTST-C190GKT"
			(at 0 1.6 0)
			(layer "F.Fab")
			(hide yes)
			(effects
				(font
					(size 0.7 0.7)
					(thickness 0.15)
				)
				(justify right top)
			)
		)
		(property "Datasheet" "https://media.digikey.com/pdf/Data%20Sheets/Lite-On%20PDFs/LTST-C190GKT.pdf"
			(at 0 0 0)
			(layer "F.Fab")
			(hide yes)
			(effects
				(font
					(size 1.27 1.27)
					(thickness 0.15)
				)
			)
		)
		(property "Description" "LED, Green, SMD, 0603, 20 mA, 2.1 V, 569 nm"
			(at 0 0 0)
			(layer "F.Fab")
			(hide yes)
			(effects
				(font
					(size 1.27 1.27)
					(thickness 0.15)
				)
			)
		)
		(property "Author" "Antmicro"
			(at 0 0 0)
			(layer "F.Fab")
			(hide yes)
			(effects
				(font
					(size 1 1)
					(thickness 0.15)
				)
			)
		)
		(property "License" "Apache-2.0"
			(at 0 0 0)
			(layer "F.Fab")
			(hide yes)
			(effects
				(font
					(size 1 1)
					(thickness 0.15)
				)
			)
		)
		(property "MPN" "LTST-C190GKT"
			(at 0 0 0)
			(layer "F.Fab")
			(hide yes)
			(effects
				(font
					(size 1 1)
					(thickness 0.15)
				)
			)
		)
		(property "Manufacturer" "Lite-On"
			(at 0 0 0)
			(layer "F.Fab")
			(hide yes)
			(effects
				(font
					(size 1 1)
					(thickness 0.15)
				)
			)
		)
		(property "Color" "Green"
			(at 0 0 180)
			(unlocked yes)
			(layer "F.Fab")
			(hide yes)
			(effects
				(font
					(size 1 1)
					(thickness 0.15)
				)
			)
		)
		(sheetname "/Peripherals/")
		(sheetfile "peripherals.kicad_sch")
		(attr smd)
		(fp_line
			(start 0.22 0.35)
			(end -0.22 0.35)
			(stroke
				(width 0.15)
				(type solid)
			)
			(layer "F.SilkS")
		)
		(fp_line
			(start 0.22 -0.35)
			(end -0.22 -0.35)
			(stroke
				(width 0.15)
				(type solid)
			)
			(layer "F.SilkS")
		)
		(fp_line
			(start 0.105328 0.201008)
			(end 0.105328 -0.198992)
			(stroke
				(width 0.1)
				(type solid)
			)
			(layer "F.SilkS")
		)
		(fp_line
			(start 0.105328 0.201008)
			(end -0.094672 0.001008)
			(stroke
				(width 0.1)
				(type solid)
			)
			(layer "F.SilkS")
		)
		(fp_line
			(start 0.105328 0.001008)
			(end 0.24 0.001)
			(stroke
				(width 0.1)
				(type solid)
			)
			(layer "F.SilkS")
		)
		(fp_line
			(start -0.094672 0.201008)
			(end -0.094672 -0.198992)
			(stroke
				(width 0.1)
				(type solid)
			)
			(layer "F.SilkS")
		)
		(fp_line
			(start -0.094672 0.001008)
			(end 0.105328 -0.198992)
			(stroke
				(width 0.1)
				(type solid)
			)
			(layer "F.SilkS")
		)
		(fp_line
			(start -0.094672 0.001008)
			(end -0.24 0.001008)
			(stroke
				(width 0.1)
				(type solid)
			)
			(layer "F.SilkS")
		)
		(fp_line
			(start -1.18 -0.319)
			(end -1.18 0.321)
			(stroke
				(width 0.15)
				(type solid)
			)
			(layer "F.SilkS")
		)
		(fp_rect
			(start 1.25 0.65)
			(end -1.25 -0.65)
			(stroke
				(width 0.05)
				(type solid)
			)
			(fill no)
			(layer "F.CrtYd")
		)
		(fp_line
			(start 0.599 0)
			(end 0.201 0)
			(stroke
				(width 0.15)
				(type solid)
			)
			(layer "F.Fab")
		)
		(fp_line
			(start 0.201 0.2)
			(end 0.201 0)
			(stroke
				(width 0.15)
				(type solid)
			)
			(layer "F.Fab")
		)
		(fp_line
			(start 0.201 0)
			(end 0.201 -0.202)
			(stroke
				(width 0.15)
				(type solid)
			)
			(layer "F.Fab")
		)
		(fp_line
			(start 0.201 -0.202)
			(end -0.101 0)
			(stroke
				(width 0.15)
				(type solid)
			)
			(layer "F.Fab")
		)
		(fp_line
			(start -0.101 0)
			(end 0.201 0.2)
			(stroke
				(width 0.15)
				(type solid)
			)
			(layer "F.Fab")
		)
		(fp_line
			(start -0.199 0.2)
			(end -0.199 0.1)
			(stroke
				(width 0.15)
				(type solid)
			)
			(layer "F.Fab")
		)
		(fp_line
			(start -0.199 0)
			(end -0.597 0)
			(stroke
				(width 0.15)
				(type solid)
			)
			(layer "F.Fab")
		)
		(fp_line
			(start -0.199 -0.202)
			(end -0.199 0.1)
			(stroke
				(width 0.15)
				(type solid)
			)
			(layer "F.Fab")
		)
		(fp_rect
			(start 0.848 0.4)
			(end -0.85 -0.402)
			(stroke
				(width 0.15)
				(type solid)
			)
			(fill no)
			(layer "F.Fab")
		)
		(fp_text user "License: Apache-2.0"
			(at -1.4224 3.599 0)
			(layer "F.Fab")
			(effects
				(font
					(size 0.7 0.7)
					(thickness 0.15)
				)
				(justify right top)
			)
		)
		(fp_text user "${REFERENCE}"
			(at -1.4224 5.999 0)
			(layer "F.Fab")
			(effects
				(font
					(size 0.7 0.7)
					(thickness 0.15)
				)
				(justify right top)
			)
		)
		(fp_text user "Author: Antmicro"
			(at -1.4224 4.799 0)
			(layer "F.Fab")
			(effects
				(font
					(size 0.7 0.7)
					(thickness 0.15)
				)
				(justify right top)
			)
		)
		(pad "1" smd roundrect
			(at -0.7 0)
			(size 0.8 1)
			(layers "F.Cu" "F.Mask" "F.Paste")
			(roundrect_rratio 0.2)
			(net 258 "Net-(D12-C)")
			(pinfunction "C")
			(pintype "passive")
		)
		(pad "2" smd roundrect
			(at 0.7 0)
			(size 0.8 1)
			(layers "F.Cu" "F.Mask" "F.Paste")
			(roundrect_rratio 0.2)
			(net 294 "Net-(D12-A)")
			(pinfunction "A")
			(pintype "passive")
		)
	)
)
